FILE_TYPE = CONNECTIVITY;
{Allegro Design Entry HDL 16.6-p007 (v16-6-112F) 10/10/2012}
"PAGE_NUMBER" = 82;
0"NC";
1"M_J_DQS_DP<17:0>";
2"M_J_DQS_DN<17:0>";
3"M_J_DQ<63:0>";
4"M_J_MA<17:0>";
5"M_J_CLK_DN<3:0>";
6"M_J_CS_N<7:0>";
7"M_J_CKE<3:0>";
8"M_J_ODT<3:0>";
9"M_J_ECC<7:0>";
10"M_J_BA<1:0>";
11"M_J_BG<1:0>";
12"M_J_CLK_DP<3:0>";
13"PVDDQ_GHJ\g";
14"PVTT_GHJ\g";
15"GND\g";
16"GND\g";
17"PVPP_GHJ\g";
18"PVPP_GHJ\g";
19"GND\g";
20"P12V_NVDIMM_GHJ\g";
21"GND\g";
22"M_J_DQS_DN<4>";
23"M_J_VREF";
24"M_J_DQ<63>";
25"M_J_DQ<62>";
26"M_J_DQ<54>";
27"M_J_DQ<52>";
28"M_J_DQ<61>";
29"M_J_DQS_DN<9>";
30"M_J_ACT_N";
31"FM_DIMM_EVENT_COD_N";
32"TP_CH_J_DIMM_J1_RFU_2";
33"TP_CH_J_DIMM_J1_RFU_0";
34"TP_CH_J_DIMM_J1_RFU_1";
35"SMB_DDR_GHJ_VPP_SCL";
36"SMB_DDR_GHJ_VPP_SDA";
37"FM_ADR_COMPLETE_GHJ_N";
38"M_J_PAR";
39"M_GHJ_RST_N";
40"M_J_C<2>";
41"M_J_BA<1>";
42"M_J_CLK_DP<2>";
43"M_J_CS_N<7>";
44"M_J_CS_N<6>";
45"M_J_CS_N<5>";
46"M_J_MA<0>";
47"M_J_MA<1>";
48"M_J_ECC<6>";
49"M_J_ECC<5>";
50"M_J_ECC<4>";
51"M_J_ECC<3>";
52"M_J_ECC<2>";
53"M_J_ECC<1>";
54"M_J_ECC<0>";
55"M_J_CKE<3>";
56"M_J_CLK_DP<3>";
57"M_J_BG<0>";
58"M_J_BG<1>";
59"M_J_BA<0>";
60"M_J_MA<2>";
61"M_J_ECC<7>";
62"M_J_ODT<2>";
63"M_J_ODT<3>";
64"M_J_CKE<2>";
65"M_J_CS_N<4>";
66"M_J_CLK_DN<2>";
67"M_J_CLK_DN<3>";
68"M_J_ALERT_N";
69"M_J_DQ<1>";
70"M_J_DQ<2>";
71"M_J_DQ<0>";
72"M_J_DQ<7>";
73"M_J_DQ<6>";
74"M_J_DQ<3>";
75"M_J_DQ<4>";
76"M_J_DQ<5>";
77"M_J_DQ<13>";
78"M_J_DQ<12>";
79"M_J_DQ<11>";
80"M_J_DQ<10>";
81"M_J_DQ<9>";
82"M_J_DQ<8>";
83"M_J_DQ<18>";
84"M_J_DQ<14>";
85"M_J_DQ<15>";
86"M_J_DQ<17>";
87"M_J_DQ<16>";
88"M_J_DQ<23>";
89"M_J_DQ<21>";
90"M_J_DQ<20>";
91"M_J_DQ<19>";
92"M_J_DQ<22>";
93"M_J_DQ<28>";
94"M_J_DQ<25>";
95"M_J_DQ<24>";
96"M_J_DQ<27>";
97"M_J_DQ<26>";
98"M_J_DQ<29>";
99"M_J_DQ<33>";
100"M_J_DQ<32>";
101"M_J_DQ<31>";
102"M_J_DQ<30>";
103"M_J_DQ<34>";
104"M_J_DQ<35>";
105"M_J_DQ<38>";
106"M_J_DQ<36>";
107"M_J_DQ<37>";
108"M_J_DQ<43>";
109"M_J_DQ<42>";
110"M_J_DQ<40>";
111"M_J_DQ<39>";
112"M_J_DQ<41>";
113"M_J_DQ<46>";
114"M_J_DQ<45>";
115"M_J_DQ<44>";
116"M_J_DQ<48>";
117"M_J_DQ<47>";
118"M_J_MA<12>";
119"M_J_MA<13>";
120"M_J_MA<17>";
121"M_J_MA<3>";
122"M_J_MA<4>";
123"M_J_MA<5>";
124"M_J_MA<6>";
125"M_J_MA<7>";
126"M_J_MA<8>";
127"M_J_MA<9>";
128"M_J_MA<10>";
129"M_J_MA<11>";
130"M_J_MA<14>";
131"M_J_MA<15>";
132"M_J_MA<16>";
133"M_J_DQ<53>";
134"M_J_DQ<51>";
135"M_J_DQ<50>";
136"M_J_DQ<49>";
137"M_J_DQ<59>";
138"M_J_DQ<56>";
139"M_J_DQ<55>";
140"M_J_DQ<57>";
141"M_J_DQ<58>";
142"M_J_DQ<60>";
143"M_J_DQS_DN<0>";
144"M_J_DQS_DP<0>";
145"M_J_DQS_DN<1>";
146"M_J_DQS_DP<1>";
147"M_J_DQS_DN<2>";
148"M_J_DQS_DP<2>";
149"M_J_DQS_DN<3>";
150"M_J_DQS_DP<3>";
151"M_J_DQS_DP<4>";
152"M_J_DQS_DN<5>";
153"M_J_DQS_DP<5>";
154"M_J_DQS_DN<6>";
155"M_J_DQS_DP<6>";
156"M_J_DQS_DN<10>";
157"M_J_DQS_DP<10>";
158"M_J_DQS_DN<11>";
159"M_J_DQS_DP<11>";
160"M_J_DQS_DN<12>";
161"M_J_DQS_DP<12>";
162"M_J_DQS_DN<13>";
163"M_J_DQS_DP<13>";
164"M_J_DQS_DN<14>";
165"M_J_DQS_DP<14>";
166"M_J_DQS_DN<15>";
167"M_J_DQS_DP<15>";
168"M_J_DQS_DN<16>";
169"M_J_DQS_DP<16>";
170"M_J_DQS_DN<17>";
171"M_J_DQS_DN<7>";
172"M_J_DQS_DP<7>";
173"M_J_DQS_DN<8>";
174"M_J_DQS_DP<8>";
175"M_J_DQS_DP<9>";
176"M_J_DQS_DP<17>";
%"TAP"
"6","(650,4950)","2","mstr_standard","I10";
;
HDL_TAP"TRUE"
BODY_TYPE"PLUMBING"
CDS_LIB"mstr_standard";
"B \NAC \NWC"1;
"S \NAC"
BN"15"167;
%"TAP"
"6","(-1750,1900)","2","mstr_standard","I100";
;
HDL_TAP"TRUE"
BODY_TYPE"PLUMBING"
CDS_LIB"mstr_standard";
"B \NAC \NWC"3;
"S \NAC"
BN"5"76;
%"TAP"
"6","(-1750,2000)","2","mstr_standard","I101";
;
HDL_TAP"TRUE"
BODY_TYPE"PLUMBING"
CDS_LIB"mstr_standard";
"B \NAC \NWC"3;
"S \NAC"
BN"7"72;
%"TAP"
"6","(-1750,1950)","2","mstr_standard","I102";
;
HDL_TAP"TRUE"
BODY_TYPE"PLUMBING"
CDS_LIB"mstr_standard";
"B \NAC \NWC"3;
"S \NAC"
BN"6"73;
%"TAP"
"6","(-1750,2050)","2","mstr_standard","I103";
;
HDL_TAP"TRUE"
BODY_TYPE"PLUMBING"
CDS_LIB"mstr_standard";
"B \NAC \NWC"3;
"S \NAC"
BN"8"82;
%"TAP"
"6","(-1750,2100)","2","mstr_standard","I104";
;
HDL_TAP"TRUE"
BODY_TYPE"PLUMBING"
CDS_LIB"mstr_standard";
"B \NAC \NWC"3;
"S \NAC"
BN"9"81;
%"TAP"
"6","(-1750,2150)","2","mstr_standard","I105";
;
HDL_TAP"TRUE"
BODY_TYPE"PLUMBING"
CDS_LIB"mstr_standard";
"B \NAC \NWC"3;
"S \NAC"
BN"10"80;
%"TAP"
"6","(-1750,1800)","2","mstr_standard","I106";
;
HDL_TAP"TRUE"
BODY_TYPE"PLUMBING"
CDS_LIB"mstr_standard";
"B \NAC \NWC"3;
"S \NAC"
BN"3"74;
%"TAP"
"6","(-1750,1850)","2","mstr_standard","I107";
;
HDL_TAP"TRUE"
BODY_TYPE"PLUMBING"
CDS_LIB"mstr_standard";
"B \NAC \NWC"3;
"S \NAC"
BN"4"75;
%"TAP"
"6","(-1750,1700)","2","mstr_standard","I108";
;
HDL_TAP"TRUE"
BODY_TYPE"PLUMBING"
CDS_LIB"mstr_standard";
"B \NAC \NWC"3;
"S \NAC"
BN"1"69;
%"TAP"
"6","(-1750,1650)","2","mstr_standard","I109";
;
HDL_TAP"TRUE"
BODY_TYPE"PLUMBING"
CDS_LIB"mstr_standard";
"B \NAC \NWC"3;
"S \NAC"
BN"0"71;
%"TAP"
"6","(650,4850)","2","mstr_standard","I11";
;
HDL_TAP"TRUE"
BODY_TYPE"PLUMBING"
CDS_LIB"mstr_standard";
"B \NAC \NWC"1;
"S \NAC"
BN"14"165;
%"TAP"
"6","(-1750,1750)","2","mstr_standard","I110";
;
HDL_TAP"TRUE"
BODY_TYPE"PLUMBING"
CDS_LIB"mstr_standard";
"B \NAC \NWC"3;
"S \NAC"
BN"2"70;
%"TAP"
"6","(-3250,4750)","0","mstr_standard","I112";
;
HDL_TAP"TRUE"
BODY_TYPE"PLUMBING"
CDS_LIB"mstr_standard";
"B \NAC \NWC"4;
"S \NAC"
BN"16"132;
%"TAP"
"6","(-3250,4800)","0","mstr_standard","I113";
;
HDL_TAP"TRUE"
BODY_TYPE"PLUMBING"
CDS_LIB"mstr_standard";
"B \NAC \NWC"4;
"S \NAC"
BN"17"120;
%"TAP"
"6","(-3250,4700)","0","mstr_standard","I114";
;
HDL_TAP"TRUE"
BODY_TYPE"PLUMBING"
CDS_LIB"mstr_standard";
"B \NAC \NWC"4;
"S \NAC"
BN"15"131;
%"TAP"
"6","(-3250,4650)","0","mstr_standard","I115";
;
HDL_TAP"TRUE"
BODY_TYPE"PLUMBING"
CDS_LIB"mstr_standard";
"B \NAC \NWC"4;
"S \NAC"
BN"14"130;
%"TAP"
"6","(-3250,4600)","0","mstr_standard","I116";
;
HDL_TAP"TRUE"
BODY_TYPE"PLUMBING"
CDS_LIB"mstr_standard";
"B \NAC \NWC"4;
"S \NAC"
BN"13"119;
%"TAP"
"6","(-3250,4500)","0","mstr_standard","I117";
;
HDL_TAP"TRUE"
BODY_TYPE"PLUMBING"
CDS_LIB"mstr_standard";
"B \NAC \NWC"4;
"S \NAC"
BN"11"129;
%"TAP"
"6","(-3250,4550)","0","mstr_standard","I118";
;
HDL_TAP"TRUE"
BODY_TYPE"PLUMBING"
CDS_LIB"mstr_standard";
"B \NAC \NWC"4;
"S \NAC"
BN"12"118;
%"TAP"
"6","(-3250,4450)","0","mstr_standard","I119";
;
HDL_TAP"TRUE"
BODY_TYPE"PLUMBING"
CDS_LIB"mstr_standard";
"B \NAC \NWC"4;
"S \NAC"
BN"10"128;
%"TAP"
"6","(650,4750)","2","mstr_standard","I12";
;
HDL_TAP"TRUE"
BODY_TYPE"PLUMBING"
CDS_LIB"mstr_standard";
"B \NAC \NWC"1;
"S \NAC"
BN"13"163;
%"TAP"
"6","(-3250,4400)","0","mstr_standard","I120";
;
HDL_TAP"TRUE"
BODY_TYPE"PLUMBING"
CDS_LIB"mstr_standard";
"B \NAC \NWC"4;
"S \NAC"
BN"9"127;
%"TAP"
"6","(-3250,4350)","0","mstr_standard","I121";
;
HDL_TAP"TRUE"
BODY_TYPE"PLUMBING"
CDS_LIB"mstr_standard";
"B \NAC \NWC"4;
"S \NAC"
BN"8"126;
%"TAP"
"6","(-3250,4250)","0","mstr_standard","I122";
;
HDL_TAP"TRUE"
BODY_TYPE"PLUMBING"
CDS_LIB"mstr_standard";
"B \NAC \NWC"4;
"S \NAC"
BN"6"124;
%"TAP"
"6","(-3250,4300)","0","mstr_standard","I123";
;
HDL_TAP"TRUE"
BODY_TYPE"PLUMBING"
CDS_LIB"mstr_standard";
"B \NAC \NWC"4;
"S \NAC"
BN"7"125;
%"TAP"
"6","(-3250,4200)","0","mstr_standard","I124";
;
HDL_TAP"TRUE"
BODY_TYPE"PLUMBING"
CDS_LIB"mstr_standard";
"B \NAC \NWC"4;
"S \NAC"
BN"5"123;
%"TAP"
"6","(-3250,4100)","0","mstr_standard","I125";
;
HDL_TAP"TRUE"
BODY_TYPE"PLUMBING"
CDS_LIB"mstr_standard";
"B \NAC \NWC"4;
"S \NAC"
BN"3"121;
%"TAP"
"6","(-3250,4150)","0","mstr_standard","I126";
;
HDL_TAP"TRUE"
BODY_TYPE"PLUMBING"
CDS_LIB"mstr_standard";
"B \NAC \NWC"4;
"S \NAC"
BN"4"122;
%"TAP"
"6","(-3250,4050)","0","mstr_standard","I127";
;
HDL_TAP"TRUE"
BODY_TYPE"PLUMBING"
CDS_LIB"mstr_standard";
"B \NAC \NWC"4;
"S \NAC"
BN"2"60;
%"TAP"
"6","(-3250,3950)","0","mstr_standard","I128";
;
HDL_TAP"TRUE"
BODY_TYPE"PLUMBING"
CDS_LIB"mstr_standard";
"B \NAC \NWC"4;
"S \NAC"
BN"0"46;
%"TAP"
"6","(-3250,4000)","0","mstr_standard","I129";
;
HDL_TAP"TRUE"
BODY_TYPE"PLUMBING"
CDS_LIB"mstr_standard";
"B \NAC \NWC"4;
"S \NAC"
BN"1"47;
%"TAP"
"6","(650,4650)","2","mstr_standard","I13";
;
HDL_TAP"TRUE"
BODY_TYPE"PLUMBING"
CDS_LIB"mstr_standard";
"B \NAC \NWC"1;
"S \NAC"
BN"12"161;
%"TAP"
"6","(-3250,3850)","0","mstr_standard","I131";
;
HDL_TAP"TRUE"
BODY_TYPE"PLUMBING"
CDS_LIB"mstr_standard";
"B \NAC \NWC"10;
"S \NAC"
BN"1"41;
%"TAP"
"6","(-3250,3800)","0","mstr_standard","I132";
;
HDL_TAP"TRUE"
BODY_TYPE"PLUMBING"
CDS_LIB"mstr_standard";
"B \NAC \NWC"10;
"S \NAC"
BN"0"59;
%"TAP"
"6","(-3250,3700)","0","mstr_standard","I133";
;
HDL_TAP"TRUE"
BODY_TYPE"PLUMBING"
CDS_LIB"mstr_standard";
"B \NAC \NWC"11;
"S \NAC"
BN"0"57;
%"TAP"
"6","(-3250,3750)","0","mstr_standard","I134";
;
HDL_TAP"TRUE"
BODY_TYPE"PLUMBING"
CDS_LIB"mstr_standard";
"B \NAC \NWC"11;
"S \NAC"
BN"1"58;
%"TAP"
"6","(-3300,2700)","0","mstr_standard","I138";
;
HDL_TAP"TRUE"
BODY_TYPE"PLUMBING"
CDS_LIB"mstr_standard";
"B \NAC \NWC"9;
"S \NAC"
BN"6"48;
%"TAP"
"6","(-3300,2750)","0","mstr_standard","I139";
;
HDL_TAP"TRUE"
BODY_TYPE"PLUMBING"
CDS_LIB"mstr_standard";
"B \NAC \NWC"9;
"S \NAC"
BN"7"61;
%"PVDDQ_GHJ"
"1","(-1400,2575)","0","mstr_symbols","I14";
;
HDL_POWER"PVDDQ_GHJ"
ROOM"DDR4_CH_J"
BODY_TYPE"PLUMBING"
CDS_LIB"mstr_symbols"
BOM_COST"MEM"
VOLTAGE"1.2V";
"G\NAC"13;
%"TAP"
"6","(-3300,2650)","0","mstr_standard","I140";
;
HDL_TAP"TRUE"
BODY_TYPE"PLUMBING"
CDS_LIB"mstr_standard";
"B \NAC \NWC"9;
"S \NAC"
BN"5"49;
%"TAP"
"6","(-3300,2600)","0","mstr_standard","I141";
;
HDL_TAP"TRUE"
BODY_TYPE"PLUMBING"
CDS_LIB"mstr_standard";
"B \NAC \NWC"9;
"S \NAC"
BN"4"50;
%"TAP"
"6","(-3300,2550)","0","mstr_standard","I142";
;
HDL_TAP"TRUE"
BODY_TYPE"PLUMBING"
CDS_LIB"mstr_standard";
"B \NAC \NWC"9;
"S \NAC"
BN"3"51;
%"TAP"
"6","(-3300,2450)","0","mstr_standard","I143";
;
HDL_TAP"TRUE"
BODY_TYPE"PLUMBING"
CDS_LIB"mstr_standard";
"B \NAC \NWC"9;
"S \NAC"
BN"1"53;
%"TAP"
"6","(-3300,2500)","0","mstr_standard","I144";
;
HDL_TAP"TRUE"
BODY_TYPE"PLUMBING"
CDS_LIB"mstr_standard";
"B \NAC \NWC"9;
"S \NAC"
BN"2"52;
%"TAP"
"6","(-3300,2400)","0","mstr_standard","I145";
;
HDL_TAP"TRUE"
BODY_TYPE"PLUMBING"
CDS_LIB"mstr_standard";
"B \NAC \NWC"9;
"S \NAC"
BN"0"54;
%"TAP"
"6","(-3250,3600)","0","mstr_standard","I152";
;
HDL_TAP"TRUE"
BODY_TYPE"PLUMBING"
CDS_LIB"mstr_standard";
"B \NAC \NWC"12;
"S \NAC"
BN"3"56;
%"TAP"
"6","(-3250,3500)","0","mstr_standard","I153";
;
HDL_TAP"TRUE"
BODY_TYPE"PLUMBING"
CDS_LIB"mstr_standard";
"B \NAC \NWC"12;
"S \NAC"
BN"2"42;
%"TAP"
"6","(-3450,3550)","0","mstr_standard","I154";
;
HDL_TAP"TRUE"
BODY_TYPE"PLUMBING"
CDS_LIB"mstr_standard";
"B \NAC \NWC"5;
"S \NAC"
BN"3"67;
%"TAP"
"6","(-3450,3450)","0","mstr_standard","I155";
;
HDL_TAP"TRUE"
BODY_TYPE"PLUMBING"
CDS_LIB"mstr_standard";
"B \NAC \NWC"5;
"S \NAC"
BN"2"66;
%"TAP"
"6","(-3300,3300)","0","mstr_standard","I158";
;
HDL_TAP"TRUE"
BODY_TYPE"PLUMBING"
CDS_LIB"mstr_standard";
"B \NAC \NWC"6;
"S \NAC"
BN"7"43;
%"TAP"
"6","(-3300,3250)","0","mstr_standard","I159";
;
HDL_TAP"TRUE"
BODY_TYPE"PLUMBING"
CDS_LIB"mstr_standard";
"B \NAC \NWC"6;
"S \NAC"
BN"6"44;
%"PVTT_GHJ"
"1","(-1200,2750)","0","mstr_symbols","I16";
;
HDL_POWER"PVTT_GHJ"
ROOM"DDR4_CH_J"
BODY_TYPE"PLUMBING"
CDS_LIB"mstr_symbols"
BOM_COST"MEM"
VOLTAGE"0.6V";
"G\NAC"14;
%"TAP"
"6","(-3300,3200)","0","mstr_standard","I160";
;
HDL_TAP"TRUE"
BODY_TYPE"PLUMBING"
CDS_LIB"mstr_standard";
"B \NAC \NWC"6;
"S \NAC"
BN"5"45;
%"TAP"
"6","(-3300,3150)","0","mstr_standard","I161";
;
HDL_TAP"TRUE"
BODY_TYPE"PLUMBING"
CDS_LIB"mstr_standard";
"B \NAC \NWC"6;
"S \NAC"
BN"4"65;
%"TAP"
"6","(-3300,3050)","0","mstr_standard","I162";
;
HDL_TAP"TRUE"
BODY_TYPE"PLUMBING"
CDS_LIB"mstr_standard";
"B \NAC \NWC"7;
"S \NAC"
BN"3"55;
%"TAP"
"6","(-3300,3000)","0","mstr_standard","I165";
;
HDL_TAP"TRUE"
BODY_TYPE"PLUMBING"
CDS_LIB"mstr_standard";
"B \NAC \NWC"7;
"S \NAC"
BN"2"64;
%"TAP"
"6","(-3300,2900)","0","mstr_standard","I166";
;
HDL_TAP"TRUE"
BODY_TYPE"PLUMBING"
CDS_LIB"mstr_standard";
"B \NAC \NWC"8;
"S \NAC"
BN"3"63;
%"TAP"
"6","(-3300,2850)","0","mstr_standard","I168";
;
HDL_TAP"TRUE"
BODY_TYPE"PLUMBING"
CDS_LIB"mstr_standard";
"B \NAC \NWC"8;
"S \NAC"
BN"2"62;
%"TAP"
"6","(850,4600)","2","mstr_standard","I17";
;
HDL_TAP"TRUE"
BODY_TYPE"PLUMBING"
CDS_LIB"mstr_standard";
"B \NAC \NWC"2;
"S \NAC"
BN"12"160;
%"SCONN288_H44441003"
"4","(-350,2050)","0","mstr_sconn","I171";
;
CDS_SEC"4"
BOM_SS"NOPOP"
MATERIAL"SCONN"
PART_NUMBER"H44441-003"
LOCATION"J9U2"
ROOM"DDR4_CH_J"
CDS_LOCATION"J9U2"
SEC"4"
SEC_TYPE"PIP"
CDS_LIB"mstr_sconn"
BOM_COST"MEM"
PACK_TYPE"PIP";
"VDD<0>"
$PN"236"13;
"VDD<6>"
$PN"220"13;
"VDD<10>"
$PN"209"13;
"VDD<13>"
$PN"92"13;
"VDD<16>"
$PN"85"13;
"VDD<19>"
$PN"76"13;
"VDD<23>"
$PN"64"13;
"VDD<25>"
$PN"59"13;
"VTT<0>"
$PN"221"14;
"12V<1>"
$PN"1"20;
"12V<0>"
$PN"145"20;
"VDD<24>"
$PN"61"13;
"VDD<22>"
$PN"67"13;
"VDD<21>"
$PN"70"13;
"VDD<20>"
$PN"73"13;
"VDD<18>"
$PN"80"13;
"VDD<17>"
$PN"83"13;
"VDD<15>"
$PN"88"13;
"VDD<14>"
$PN"90"13;
"VDD<12>"
$PN"204"13;
"VDD<11>"
$PN"206"13;
"VDD<9>"
$PN"212"13;
"VDD<8>"
$PN"215"13;
"VDD<7>"
$PN"217"13;
"VDD<5>"
$PN"223"13;
"VDD<4>"
$PN"226"13;
"VDD<3>"
$PN"229"13;
"VDD<2>"
$PN"231"13;
"VDD<1>"
$PN"233"13;
"VPP<4>"
$PN"142"17;
"VPP<3>"
$PN"143"17;
"VPP<2>"
$PN"288"17;
"VPP<1>"
$PN"286"17;
"VPP<0>"
$PN"287"17;
"VTT<1>"
$PN"77"14;
%"GND"
"1","(2450,1050)","2","mstr_symbols","I172";
;
HDL_POWER"GND"
ROOM"DDR4_CH_J"
BODY_TYPE"PLUMBING"
BOM_COST"MEM"
CDS_LIB"mstr_symbols"
SIZE"1B"
VOLTAGE"0";
"A\NAC"15;
%"GND"
"1","(-4500,1150)","0","mstr_symbols","I179";
;
HDL_POWER"GND"
ROOM"DDR4_CH_J"
BODY_TYPE"PLUMBING"
BOM_COST"MEM"
SIZE"1B"
CDS_LIB"mstr_symbols"
VOLTAGE"0";
"A\NAC"16;
%"TAP"
"6","(850,4500)","2","mstr_standard","I18";
;
HDL_TAP"TRUE"
BODY_TYPE"PLUMBING"
CDS_LIB"mstr_standard";
"B \NAC \NWC"2;
"S \NAC"
BN"11"158;
%"CAP_A"
"1","(-4500,1450)","2","dev_discrete","I180";
;
MATERIAL"X7R"
VOLTAGE"25V"
PACK_TYPE"0402V"
TOLERANCE"10%"
VALUE"0.01UF"
PART_NUMBER"A36096-045"
LOCATION"C1G19"
ROOM"DDR4_CH_J"
$SEC"1"
CDS_SEC"1"
CDS_LIB"dev_discrete"
BOM_COST"MEM"
CDS_LOCATION"C1G19";
"B"
$PN"2"16;
"A"
$PN"1"23;
%"PVPP_GHJ"
"1","(-1050,3025)","0","mstr_symbols","I181";
;
HDL_POWER"PVPP_GHJ"
ROOM"DDR4_CH_K"
BODY_TYPE"PLUMBING"
CDS_LIB"mstr_symbols"
BOM_COST"MEM"
VOLTAGE"2.5V";
"G\NAC"17;
%"PVPP_GHJ"
"1","(-5200,2150)","0","mstr_symbols","I182";
;
HDL_POWER"PVPP_GHJ"
ROOM"DDR4_CH_J"
BODY_TYPE"PLUMBING"
CDS_LIB"mstr_symbols"
BOM_COST"MEM"
VOLTAGE"2.5V";
"G\NAC"18;
%"SCONN288_H44441003"
"1","(-2500,3150)","0","mstr_sconn","I187";
;
CDS_SEC"1"
MATERIAL"SCONN"
BOM_SS"NOPOP"
PART_NUMBER"H44441-003"
LOCATION"J9U2"
ROOM"DDR4_CH_J"
CDS_LOCATION"J9U2"
SEC"1"
SEC_TYPE"PIP"
CDS_LIB"mstr_sconn"
BOM_COST"MEM"
PACK_TYPE"PIP";
"DQ<63>"
$PN"280"24;
"BA<1>"
$PN"224"41;
"CK1N"
$PN"219"67;
"CK0P"
$PN"74"42;
"S3_N_C<1>"
$PN"237"43;
"S2_N_C<0>"
$PN"93"44;
"S1_N"
$PN"89"45;
"DQ<29>"
$PN"181"98;
"DQ<28>"
$PN"36"93;
"C<2>"
$PN"235"40;
"A0"
$PN"79"46;
"A1"
$PN"72"47;
"A12"
$PN"65"118;
"A13"
$PN"232"119;
"A17"
$PN"234"120;
"A3"
$PN"71"121;
"A4"
$PN"214"122;
"A5"
$PN"213"123;
"A6"
$PN"69"124;
"A7"
$PN"211"125;
"A8"
$PN"68"126;
"A9"
$PN"66"127;
"CB<6>"
$PN"54"48;
"CB<5>"
$PN"192"49;
"CB<4>"
$PN"47"50;
"CB<3>"
$PN"201"51;
"CB<2>"
$PN"56"52;
"CB<1>"
$PN"194"53;
"CB<0>"
$PN"49"54;
"CK0N"
$PN"75"66;
"CKE<1>"
$PN"203"55;
"DQ<62>"
$PN"135"25;
"DQ<61>"
$PN"273"28;
"DQ<60>"
$PN"128"142;
"DQ<59>"
$PN"282"137;
"DQ<56>"
$PN"130"138;
"DQ<55>"
$PN"269"139;
"DQ<46>"
$PN"113"113;
"DQ<45>"
$PN"251"114;
"DQ<44>"
$PN"106"115;
"DQ<43>"
$PN"260"108;
"DQ<42>"
$PN"115"109;
"DQ<41>"
$PN"253"112;
"DQ<40>"
$PN"108"110;
"DQ<39>"
$PN"247"111;
"DQ<37>"
$PN"240"107;
"DQ<34>"
$PN"104"103;
"DQ<33>"
$PN"242"99;
"DQ<32>"
$PN"97"100;
"DQ<31>"
$PN"188"101;
"DQ<30>"
$PN"43"102;
"DQ<25>"
$PN"183"94;
"DQ<24>"
$PN"38"95;
"DQ<23>"
$PN"177"88;
"DQ<22>"
$PN"32"92;
"DQ<21>"
$PN"170"89;
"DQ<20>"
$PN"25"90;
"DQ<19>"
$PN"179"91;
"DQ<18>"
$PN"34"83;
"DQ<16>"
$PN"27"87;
"DQ<14>"
$PN"21"84;
"DQ<13>"
$PN"159"77;
"DQ<12>"
$PN"14"78;
"DQ<11>"
$PN"168"79;
"DQ<10>"
$PN"23"80;
"DQ<9>"
$PN"161"81;
"DQ<8>"
$PN"16"82;
"DQ<7>"
$PN"155"72;
"DQ<6>"
$PN"10"73;
"EVENT_N"
$PN"78"31;
"PAR"
$PN"222"38;
"RESET_N"
$PN"58"39;
"RFU<2>"
$PN"144"32;
"SCL"
$PN"141"35;
"SDA"
$PN"285"36;
"VREFCA"
$PN"146"23;
"CK1P"
$PN"218"56;
"BG<0>"
$PN"63"57;
"BG<1>"
$PN"207"58;
"BA<0>"
$PN"81"59;
"SA<0>"
$PN"139"18;
"VDDSPD"
$PN"284"18;
"SA<2>"
$PN"238"18;
"SA<1>"
$PN"140"19;
"DQ<1>"
$PN"150"69;
"DQ<0>"
$PN"5"71;
"ACT_N"
$PN"62"30;
"ALERT_N"
$PN"208"68;
"A2"
$PN"216"60;
"DQ<35>"
$PN"249"104;
"DQ<36>"
$PN"95"106;
"DQ<38>"
$PN"102"105;
"A10"
$PN"225"128;
"A11"
$PN"210"129;
"A14_WE_N"
$PN"228"130;
"A15_CAS_N"
$PN"86"131;
"A16_RAS_N"
$PN"82"132;
"CB<7>"
$PN"199"61;
"ODT<0>"
$PN"87"62;
"ODT<1>"
$PN"91"63;
"CKE<0>"
$PN"60"64;
"S0_N"
$PN"84"65;
"DQ<27>"
$PN"190"96;
"DQ<26>"
$PN"45"97;
"DQ<15>"
$PN"166"85;
"DQ<17>"
$PN"172"86;
"RFU<0>"
$PN"205"33;
"RFU<1>"
$PN"227"34;
"SAVE_N_NC"
$PN"230"37;
"DQ<57>"
$PN"275"140;
"DQ<58>"
$PN"137"141;
"DQ<54>"
$PN"124"26;
"DQ<53>"
$PN"262"133;
"DQ<52>"
$PN"117"27;
"DQ<51>"
$PN"271"134;
"DQ<50>"
$PN"126"135;
"DQ<49>"
$PN"264"136;
"DQ<48>"
$PN"119"116;
"DQ<47>"
$PN"258"117;
"DQ<2>"
$PN"12"70;
"DQ<3>"
$PN"157"74;
"DQ<4>"
$PN"3"75;
"DQ<5>"
$PN"148"76;
%"SCONN288_H44441003"
"3","(1750,2350)","0","mstr_sconn","I188";
;
CDS_SEC"3"
BOM_SS"NOPOP"
MATERIAL"SCONN"
PART_NUMBER"H44441-003"
LOCATION"J9U2"
ROOM"DDR4_CH_J"
CDS_LOCATION"J9U2"
SEC"3"
SEC_TYPE"PIP"
CDS_LIB"mstr_sconn"
BOM_COST"MEM"
PACK_TYPE"PIP";
"VSS<46>"
$PN"147"15;
"VSS<45>"
$PN"149"15;
"VSS<87>"
$PN"15"21;
"VSS<86>"
$PN"17"21;
"VSS<85>"
$PN"20"21;
"VSS<84>"
$PN"22"21;
"VSS<83>"
$PN"24"21;
"VSS<82>"
$PN"26"21;
"VSS<81>"
$PN"28"21;
"VSS<80>"
$PN"31"21;
"VSS<79>"
$PN"33"21;
"VSS<78>"
$PN"35"21;
"VSS<77>"
$PN"37"21;
"VSS<76>"
$PN"39"21;
"VSS<75>"
$PN"42"21;
"VSS<74>"
$PN"44"21;
"VSS<73>"
$PN"46"21;
"VSS<72>"
$PN"48"21;
"VSS<71>"
$PN"50"21;
"VSS<70>"
$PN"53"21;
"VSS<69>"
$PN"55"21;
"VSS<68>"
$PN"57"21;
"VSS<67>"
$PN"94"21;
"VSS<66>"
$PN"96"21;
"VSS<65>"
$PN"98"21;
"VSS<64>"
$PN"101"21;
"VSS<63>"
$PN"103"21;
"VSS<62>"
$PN"105"21;
"VSS<61>"
$PN"107"21;
"VSS<60>"
$PN"109"21;
"VSS<59>"
$PN"112"21;
"VSS<58>"
$PN"114"21;
"VSS<57>"
$PN"116"21;
"VSS<56>"
$PN"118"21;
"VSS<55>"
$PN"120"21;
"VSS<54>"
$PN"123"21;
"VSS<53>"
$PN"125"21;
"VSS<52>"
$PN"127"21;
"VSS<51>"
$PN"129"21;
"VSS<50>"
$PN"131"21;
"VSS<49>"
$PN"134"21;
"VSS<48>"
$PN"136"21;
"VSS<47>"
$PN"138"21;
"VSS<44>"
$PN"151"15;
"VSS<43>"
$PN"154"15;
"VSS<42>"
$PN"156"15;
"VSS<41>"
$PN"158"15;
"VSS<40>"
$PN"160"15;
"VSS<39>"
$PN"162"15;
"VSS<38>"
$PN"165"15;
"VSS<37>"
$PN"167"15;
"VSS<36>"
$PN"169"15;
"VSS<35>"
$PN"171"15;
"VSS<34>"
$PN"173"15;
"VSS<33>"
$PN"176"15;
"VSS<32>"
$PN"178"15;
"VSS<31>"
$PN"180"15;
"VSS<30>"
$PN"182"15;
"VSS<29>"
$PN"184"15;
"VSS<28>"
$PN"187"15;
"VSS<27>"
$PN"189"15;
"VSS<26>"
$PN"191"15;
"VSS<25>"
$PN"193"15;
"VSS<24>"
$PN"195"15;
"VSS<23>"
$PN"198"15;
"VSS<22>"
$PN"200"15;
"VSS<21>"
$PN"202"15;
"VSS<20>"
$PN"239"15;
"VSS<19>"
$PN"241"15;
"VSS<18>"
$PN"243"15;
"VSS<17>"
$PN"246"15;
"VSS<16>"
$PN"248"15;
"VSS<15>"
$PN"250"15;
"VSS<14>"
$PN"252"15;
"VSS<13>"
$PN"254"15;
"VSS<12>"
$PN"257"15;
"VSS<11>"
$PN"259"15;
"VSS<10>"
$PN"261"15;
"VSS<9>"
$PN"263"15;
"VSS<8>"
$PN"265"15;
"VSS<7>"
$PN"268"15;
"VSS<6>"
$PN"270"15;
"VSS<5>"
$PN"272"15;
"VSS<4>"
$PN"274"15;
"VSS<3>"
$PN"276"15;
"VSS<2>"
$PN"279"15;
"VSS<1>"
$PN"281"15;
"VSS<0>"
$PN"283"15;
"VSS<88>"
$PN"13"21;
"VSS<89>"
$PN"11"21;
"VSS<90>"
$PN"9"21;
"VSS<91>"
$PN"6"21;
"VSS<92>"
$PN"4"21;
"VSS<93>"
$PN"2"21;
%"GND"
"1","(-5200,1800)","0","mstr_symbols","I189";
;
HDL_POWER"GND"
ROOM"DDR4_CH_J"
BODY_TYPE"PLUMBING"
CDS_LIB"mstr_symbols"
SIZE"1B"
BOM_COST"MEM"
VOLTAGE"0";
"A\NAC"19;
%"TAP"
"6","(850,4400)","2","mstr_standard","I19";
;
HDL_TAP"TRUE"
BODY_TYPE"PLUMBING"
CDS_LIB"mstr_standard";
"B \NAC \NWC"2;
"S \NAC"
BN"10"156;
%"P12V_NVDIMM_GHJ"
"1","(350,3025)","0","mstr_symbols","I190";
;
HDL_POWER"P12V_NVDIMM_GHJ"
BODY_TYPE"PLUMBING"
CDS_LIB"mstr_symbols"
VOLTAGE"12.0";
"G\NAC"20;
%"TAP"
"6","(850,4200)","2","mstr_standard","I20";
;
HDL_TAP"TRUE"
BODY_TYPE"PLUMBING"
CDS_LIB"mstr_standard";
"B \NAC \NWC"2;
"S \NAC"
BN"8"173;
%"TAP"
"6","(850,4300)","2","mstr_standard","I21";
;
HDL_TAP"TRUE"
BODY_TYPE"PLUMBING"
CDS_LIB"mstr_standard";
"B \NAC \NWC"2;
"S \NAC"
BN"9"29;
%"TAP"
"6","(650,4550)","2","mstr_standard","I22";
;
HDL_TAP"TRUE"
BODY_TYPE"PLUMBING"
CDS_LIB"mstr_standard";
"B \NAC \NWC"1;
"S \NAC"
BN"11"159;
%"TAP"
"6","(650,4450)","2","mstr_standard","I23";
;
HDL_TAP"TRUE"
BODY_TYPE"PLUMBING"
CDS_LIB"mstr_standard";
"B \NAC \NWC"1;
"S \NAC"
BN"10"157;
%"TAP"
"6","(650,4350)","2","mstr_standard","I24";
;
HDL_TAP"TRUE"
BODY_TYPE"PLUMBING"
CDS_LIB"mstr_standard";
"B \NAC \NWC"1;
"S \NAC"
BN"9"175;
%"TAP"
"6","(650,4250)","2","mstr_standard","I25";
;
HDL_TAP"TRUE"
BODY_TYPE"PLUMBING"
CDS_LIB"mstr_standard";
"B \NAC \NWC"1;
"S \NAC"
BN"8"174;
%"TAP"
"6","(650,4150)","2","mstr_standard","I26";
;
HDL_TAP"TRUE"
BODY_TYPE"PLUMBING"
CDS_LIB"mstr_standard";
"B \NAC \NWC"1;
"S \NAC"
BN"7"172;
%"TAP"
"6","(850,4100)","2","mstr_standard","I27";
;
HDL_TAP"TRUE"
BODY_TYPE"PLUMBING"
CDS_LIB"mstr_standard";
"B \NAC \NWC"2;
"S \NAC"
BN"7"171;
%"TAP"
"6","(850,4000)","2","mstr_standard","I28";
;
HDL_TAP"TRUE"
BODY_TYPE"PLUMBING"
CDS_LIB"mstr_standard";
"B \NAC \NWC"2;
"S \NAC"
BN"6"154;
%"TAP"
"6","(850,3900)","2","mstr_standard","I29";
;
HDL_TAP"TRUE"
BODY_TYPE"PLUMBING"
CDS_LIB"mstr_standard";
"B \NAC \NWC"2;
"S \NAC"
BN"5"152;
%"TAP"
"6","(850,5100)","2","mstr_standard","I3";
;
HDL_TAP"TRUE"
BODY_TYPE"PLUMBING"
CDS_LIB"mstr_standard";
"B \NAC \NWC"2;
"S \NAC"
BN"17"170;
%"TAP"
"6","(850,3700)","2","mstr_standard","I30";
;
HDL_TAP"TRUE"
BODY_TYPE"PLUMBING"
CDS_LIB"mstr_standard";
"B \NAC \NWC"2;
"S \NAC"
BN"3"149;
%"TAP"
"6","(850,3800)","2","mstr_standard","I31";
;
HDL_TAP"TRUE"
BODY_TYPE"PLUMBING"
CDS_LIB"mstr_standard";
"B \NAC \NWC"2;
"S \NAC"
BN"4"22;
%"TAP"
"6","(650,4050)","2","mstr_standard","I32";
;
HDL_TAP"TRUE"
BODY_TYPE"PLUMBING"
CDS_LIB"mstr_standard";
"B \NAC \NWC"1;
"S \NAC"
BN"6"155;
%"TAP"
"6","(650,3950)","2","mstr_standard","I33";
;
HDL_TAP"TRUE"
BODY_TYPE"PLUMBING"
CDS_LIB"mstr_standard";
"B \NAC \NWC"1;
"S \NAC"
BN"5"153;
%"TAP"
"6","(650,3850)","2","mstr_standard","I34";
;
HDL_TAP"TRUE"
BODY_TYPE"PLUMBING"
CDS_LIB"mstr_standard";
"B \NAC \NWC"1;
"S \NAC"
BN"4"151;
%"TAP"
"6","(650,3750)","2","mstr_standard","I35";
;
HDL_TAP"TRUE"
BODY_TYPE"PLUMBING"
CDS_LIB"mstr_standard";
"B \NAC \NWC"1;
"S \NAC"
BN"3"150;
%"TAP"
"6","(650,3650)","2","mstr_standard","I36";
;
HDL_TAP"TRUE"
BODY_TYPE"PLUMBING"
CDS_LIB"mstr_standard";
"B \NAC \NWC"1;
"S \NAC"
BN"2"148;
%"TAP"
"6","(850,3500)","2","mstr_standard","I37";
;
HDL_TAP"TRUE"
BODY_TYPE"PLUMBING"
CDS_LIB"mstr_standard";
"B \NAC \NWC"2;
"S \NAC"
BN"1"145;
%"TAP"
"6","(850,3600)","2","mstr_standard","I38";
;
HDL_TAP"TRUE"
BODY_TYPE"PLUMBING"
CDS_LIB"mstr_standard";
"B \NAC \NWC"2;
"S \NAC"
BN"2"147;
%"TAP"
"6","(850,3400)","2","mstr_standard","I39";
;
HDL_TAP"TRUE"
BODY_TYPE"PLUMBING"
CDS_LIB"mstr_standard";
"B \NAC \NWC"2;
"S \NAC"
BN"0"143;
%"TAP"
"6","(850,5000)","2","mstr_standard","I4";
;
HDL_TAP"TRUE"
BODY_TYPE"PLUMBING"
CDS_LIB"mstr_standard";
"B \NAC \NWC"2;
"S \NAC"
BN"16"168;
%"TAP"
"6","(650,3550)","2","mstr_standard","I40";
;
HDL_TAP"TRUE"
BODY_TYPE"PLUMBING"
CDS_LIB"mstr_standard";
"B \NAC \NWC"1;
"S \NAC"
BN"1"146;
%"TAP"
"6","(650,3450)","2","mstr_standard","I41";
;
HDL_TAP"TRUE"
BODY_TYPE"PLUMBING"
CDS_LIB"mstr_standard";
"B \NAC \NWC"1;
"S \NAC"
BN"0"144;
%"GND"
"1","(1050,1050)","2","mstr_symbols","I44";
;
HDL_POWER"GND"
ROOM"DDR4_CH_J"
BODY_TYPE"PLUMBING"
BOM_COST"MEM"
CDS_LIB"mstr_symbols"
SIZE"1B"
VOLTAGE"0";
"A\NAC"21;
%"TAP"
"6","(-1750,4750)","2","mstr_standard","I46";
;
HDL_TAP"TRUE"
BODY_TYPE"PLUMBING"
CDS_LIB"mstr_standard";
"B \NAC \NWC"3;
"S \NAC"
BN"62"25;
%"TAP"
"6","(-1750,4800)","2","mstr_standard","I47";
;
HDL_TAP"TRUE"
BODY_TYPE"PLUMBING"
CDS_LIB"mstr_standard";
"B \NAC \NWC"3;
"S \NAC"
BN"63"24;
%"TAP"
"6","(-1750,4650)","2","mstr_standard","I48";
;
HDL_TAP"TRUE"
BODY_TYPE"PLUMBING"
CDS_LIB"mstr_standard";
"B \NAC \NWC"3;
"S \NAC"
BN"60"142;
%"TAP"
"6","(-1750,4700)","2","mstr_standard","I49";
;
HDL_TAP"TRUE"
BODY_TYPE"PLUMBING"
CDS_LIB"mstr_standard";
"B \NAC \NWC"3;
"S \NAC"
BN"61"28;
%"TAP"
"6","(850,4900)","2","mstr_standard","I5";
;
HDL_TAP"TRUE"
BODY_TYPE"PLUMBING"
CDS_LIB"mstr_standard";
"B \NAC \NWC"2;
"S \NAC"
BN"15"166;
%"TAP"
"6","(-1750,4600)","2","mstr_standard","I50";
;
HDL_TAP"TRUE"
BODY_TYPE"PLUMBING"
CDS_LIB"mstr_standard";
"B \NAC \NWC"3;
"S \NAC"
BN"59"137;
%"TAP"
"6","(-1750,4550)","2","mstr_standard","I51";
;
HDL_TAP"TRUE"
BODY_TYPE"PLUMBING"
CDS_LIB"mstr_standard";
"B \NAC \NWC"3;
"S \NAC"
BN"58"141;
%"TAP"
"6","(-1750,4500)","2","mstr_standard","I52";
;
HDL_TAP"TRUE"
BODY_TYPE"PLUMBING"
CDS_LIB"mstr_standard";
"B \NAC \NWC"3;
"S \NAC"
BN"57"140;
%"TAP"
"6","(-1750,4300)","2","mstr_standard","I53";
;
HDL_TAP"TRUE"
BODY_TYPE"PLUMBING"
CDS_LIB"mstr_standard";
"B \NAC \NWC"3;
"S \NAC"
BN"53"133;
%"TAP"
"6","(-1750,4350)","2","mstr_standard","I54";
;
HDL_TAP"TRUE"
BODY_TYPE"PLUMBING"
CDS_LIB"mstr_standard";
"B \NAC \NWC"3;
"S \NAC"
BN"54"26;
%"TAP"
"6","(-1750,4250)","2","mstr_standard","I55";
;
HDL_TAP"TRUE"
BODY_TYPE"PLUMBING"
CDS_LIB"mstr_standard";
"B \NAC \NWC"3;
"S \NAC"
BN"52"27;
%"TAP"
"6","(-1750,4400)","2","mstr_standard","I56";
;
HDL_TAP"TRUE"
BODY_TYPE"PLUMBING"
CDS_LIB"mstr_standard";
"B \NAC \NWC"3;
"S \NAC"
BN"55"139;
%"TAP"
"6","(-1750,4450)","2","mstr_standard","I57";
;
HDL_TAP"TRUE"
BODY_TYPE"PLUMBING"
CDS_LIB"mstr_standard";
"B \NAC \NWC"3;
"S \NAC"
BN"56"138;
%"TAP"
"6","(-1750,4000)","2","mstr_standard","I58";
;
HDL_TAP"TRUE"
BODY_TYPE"PLUMBING"
CDS_LIB"mstr_standard";
"B \NAC \NWC"3;
"S \NAC"
BN"47"117;
%"TAP"
"6","(-1750,4050)","2","mstr_standard","I59";
;
HDL_TAP"TRUE"
BODY_TYPE"PLUMBING"
CDS_LIB"mstr_standard";
"B \NAC \NWC"3;
"S \NAC"
BN"48"116;
%"TAP"
"6","(850,4800)","2","mstr_standard","I6";
;
HDL_TAP"TRUE"
BODY_TYPE"PLUMBING"
CDS_LIB"mstr_standard";
"B \NAC \NWC"2;
"S \NAC"
BN"14"164;
%"TAP"
"6","(-1750,3950)","2","mstr_standard","I60";
;
HDL_TAP"TRUE"
BODY_TYPE"PLUMBING"
CDS_LIB"mstr_standard";
"B \NAC \NWC"3;
"S \NAC"
BN"46"113;
%"TAP"
"6","(-1750,4100)","2","mstr_standard","I61";
;
HDL_TAP"TRUE"
BODY_TYPE"PLUMBING"
CDS_LIB"mstr_standard";
"B \NAC \NWC"3;
"S \NAC"
BN"49"136;
%"TAP"
"6","(-1750,4150)","2","mstr_standard","I62";
;
HDL_TAP"TRUE"
BODY_TYPE"PLUMBING"
CDS_LIB"mstr_standard";
"B \NAC \NWC"3;
"S \NAC"
BN"50"135;
%"TAP"
"6","(-1750,4200)","2","mstr_standard","I63";
;
HDL_TAP"TRUE"
BODY_TYPE"PLUMBING"
CDS_LIB"mstr_standard";
"B \NAC \NWC"3;
"S \NAC"
BN"51"134;
%"SCONN288_H44441003"
"2","(-50,4300)","0","mstr_sconn","I64";
;
CDS_SEC"2"
BOM_SS"NOPOP"
MATERIAL"SCONN"
PART_NUMBER"H44441-003"
LOCATION"J9U2"
ROOM"DDR4_CH_J"
CDS_LOCATION"J9U2"
SEC"2"
SEC_TYPE"PIP"
CDS_LIB"mstr_sconn"
BOM_COST"MEM"
PACK_TYPE"PIP";
"DQS0N"
$PN"152"143;
"DQS0P"
$PN"153"144;
"DQS10N"
$PN"19"156;
"DQS10P"
$PN"18"157;
"DQS11N"
$PN"30"158;
"DQS11P"
$PN"29"159;
"DQS12N"
$PN"41"160;
"DQS12P"
$PN"40"161;
"DQS13N"
$PN"100"162;
"DQS13P"
$PN"99"163;
"DQS14N"
$PN"111"164;
"DQS14P"
$PN"110"165;
"DQS15N"
$PN"122"166;
"DQS15P"
$PN"121"167;
"DQS16N"
$PN"133"168;
"DQS16P"
$PN"132"169;
"DQS17N"
$PN"52"170;
"DQS17P"
$PN"51"176;
"DQS1N"
$PN"163"145;
"DQS1P"
$PN"164"146;
"DQS2N"
$PN"174"147;
"DQS2P"
$PN"175"148;
"DQS3N"
$PN"185"149;
"DQS3P"
$PN"186"150;
"DQS4N"
$PN"244"22;
"DQS4P"
$PN"245"151;
"DQS5N"
$PN"255"152;
"DQS5P"
$PN"256"153;
"DQS6N"
$PN"266"154;
"DQS6P"
$PN"267"155;
"DQS7N"
$PN"277"171;
"DQS7P"
$PN"278"172;
"DQS8N"
$PN"196"173;
"DQS8P"
$PN"197"174;
"DQS9N"
$PN"8"29;
"DQS9P"
$PN"7"175;
%"TAP"
"6","(-1750,3800)","2","mstr_standard","I65";
;
HDL_TAP"TRUE"
BODY_TYPE"PLUMBING"
CDS_LIB"mstr_standard";
"B \NAC \NWC"3;
"S \NAC"
BN"43"108;
%"TAP"
"6","(-1750,3750)","2","mstr_standard","I66";
;
HDL_TAP"TRUE"
BODY_TYPE"PLUMBING"
CDS_LIB"mstr_standard";
"B \NAC \NWC"3;
"S \NAC"
BN"42"109;
%"TAP"
"6","(-1750,3700)","2","mstr_standard","I67";
;
HDL_TAP"TRUE"
BODY_TYPE"PLUMBING"
CDS_LIB"mstr_standard";
"B \NAC \NWC"3;
"S \NAC"
BN"41"112;
%"TAP"
"6","(-1750,3850)","2","mstr_standard","I68";
;
HDL_TAP"TRUE"
BODY_TYPE"PLUMBING"
CDS_LIB"mstr_standard";
"B \NAC \NWC"3;
"S \NAC"
BN"44"115;
%"TAP"
"6","(-1750,3900)","2","mstr_standard","I69";
;
HDL_TAP"TRUE"
BODY_TYPE"PLUMBING"
CDS_LIB"mstr_standard";
"B \NAC \NWC"3;
"S \NAC"
BN"45"114;
%"TAP"
"6","(850,4700)","2","mstr_standard","I7";
;
HDL_TAP"TRUE"
BODY_TYPE"PLUMBING"
CDS_LIB"mstr_standard";
"B \NAC \NWC"2;
"S \NAC"
BN"13"162;
%"TAP"
"6","(-1750,3550)","2","mstr_standard","I70";
;
HDL_TAP"TRUE"
BODY_TYPE"PLUMBING"
CDS_LIB"mstr_standard";
"B \NAC \NWC"3;
"S \NAC"
BN"38"105;
%"TAP"
"6","(-1750,3500)","2","mstr_standard","I71";
;
HDL_TAP"TRUE"
BODY_TYPE"PLUMBING"
CDS_LIB"mstr_standard";
"B \NAC \NWC"3;
"S \NAC"
BN"37"107;
%"TAP"
"6","(-1750,3450)","2","mstr_standard","I72";
;
HDL_TAP"TRUE"
BODY_TYPE"PLUMBING"
CDS_LIB"mstr_standard";
"B \NAC \NWC"3;
"S \NAC"
BN"36"106;
%"TAP"
"6","(-1750,3650)","2","mstr_standard","I73";
;
HDL_TAP"TRUE"
BODY_TYPE"PLUMBING"
CDS_LIB"mstr_standard";
"B \NAC \NWC"3;
"S \NAC"
BN"40"110;
%"TAP"
"6","(-1750,3600)","2","mstr_standard","I74";
;
HDL_TAP"TRUE"
BODY_TYPE"PLUMBING"
CDS_LIB"mstr_standard";
"B \NAC \NWC"3;
"S \NAC"
BN"39"111;
%"TAP"
"6","(-1750,3300)","2","mstr_standard","I75";
;
HDL_TAP"TRUE"
BODY_TYPE"PLUMBING"
CDS_LIB"mstr_standard";
"B \NAC \NWC"3;
"S \NAC"
BN"33"99;
%"TAP"
"6","(-1750,3250)","2","mstr_standard","I76";
;
HDL_TAP"TRUE"
BODY_TYPE"PLUMBING"
CDS_LIB"mstr_standard";
"B \NAC \NWC"3;
"S \NAC"
BN"32"100;
%"TAP"
"6","(-1750,3200)","2","mstr_standard","I77";
;
HDL_TAP"TRUE"
BODY_TYPE"PLUMBING"
CDS_LIB"mstr_standard";
"B \NAC \NWC"3;
"S \NAC"
BN"31"101;
%"TAP"
"6","(-1750,3400)","2","mstr_standard","I78";
;
HDL_TAP"TRUE"
BODY_TYPE"PLUMBING"
CDS_LIB"mstr_standard";
"B \NAC \NWC"3;
"S \NAC"
BN"35"104;
%"TAP"
"6","(-1750,3350)","2","mstr_standard","I79";
;
HDL_TAP"TRUE"
BODY_TYPE"PLUMBING"
CDS_LIB"mstr_standard";
"B \NAC \NWC"3;
"S \NAC"
BN"34"103;
%"TAP"
"6","(650,5050)","2","mstr_standard","I8";
;
HDL_TAP"TRUE"
BODY_TYPE"PLUMBING"
CDS_LIB"mstr_standard";
"B \NAC \NWC"1;
"S \NAC"
BN"16"169;
%"TAP"
"6","(-1750,3000)","2","mstr_standard","I80";
;
HDL_TAP"TRUE"
BODY_TYPE"PLUMBING"
CDS_LIB"mstr_standard";
"B \NAC \NWC"3;
"S \NAC"
BN"27"96;
%"TAP"
"6","(-1750,3050)","2","mstr_standard","I81";
;
HDL_TAP"TRUE"
BODY_TYPE"PLUMBING"
CDS_LIB"mstr_standard";
"B \NAC \NWC"3;
"S \NAC"
BN"28"93;
%"TAP"
"6","(-1750,2950)","2","mstr_standard","I82";
;
HDL_TAP"TRUE"
BODY_TYPE"PLUMBING"
CDS_LIB"mstr_standard";
"B \NAC \NWC"3;
"S \NAC"
BN"26"97;
%"TAP"
"6","(-1750,3100)","2","mstr_standard","I83";
;
HDL_TAP"TRUE"
BODY_TYPE"PLUMBING"
CDS_LIB"mstr_standard";
"B \NAC \NWC"3;
"S \NAC"
BN"29"98;
%"TAP"
"6","(-1750,3150)","2","mstr_standard","I84";
;
HDL_TAP"TRUE"
BODY_TYPE"PLUMBING"
CDS_LIB"mstr_standard";
"B \NAC \NWC"3;
"S \NAC"
BN"30"102;
%"TAP"
"6","(-1750,2750)","2","mstr_standard","I85";
;
HDL_TAP"TRUE"
BODY_TYPE"PLUMBING"
CDS_LIB"mstr_standard";
"B \NAC \NWC"3;
"S \NAC"
BN"22"92;
%"TAP"
"6","(-1750,2800)","2","mstr_standard","I86";
;
HDL_TAP"TRUE"
BODY_TYPE"PLUMBING"
CDS_LIB"mstr_standard";
"B \NAC \NWC"3;
"S \NAC"
BN"23"88;
%"TAP"
"6","(-1750,2700)","2","mstr_standard","I87";
;
HDL_TAP"TRUE"
BODY_TYPE"PLUMBING"
CDS_LIB"mstr_standard";
"B \NAC \NWC"3;
"S \NAC"
BN"21"89;
%"TAP"
"6","(-1750,2900)","2","mstr_standard","I88";
;
HDL_TAP"TRUE"
BODY_TYPE"PLUMBING"
CDS_LIB"mstr_standard";
"B \NAC \NWC"3;
"S \NAC"
BN"25"94;
%"TAP"
"6","(-1750,2850)","2","mstr_standard","I89";
;
HDL_TAP"TRUE"
BODY_TYPE"PLUMBING"
CDS_LIB"mstr_standard";
"B \NAC \NWC"3;
"S \NAC"
BN"24"95;
%"TAP"
"6","(650,5150)","2","mstr_standard","I9";
;
HDL_TAP"TRUE"
BODY_TYPE"PLUMBING"
CDS_LIB"mstr_standard";
"B \NAC \NWC"1;
"S \NAC"
BN"17"176;
%"TAP"
"6","(-1750,2450)","2","mstr_standard","I90";
;
HDL_TAP"TRUE"
BODY_TYPE"PLUMBING"
CDS_LIB"mstr_standard";
"B \NAC \NWC"3;
"S \NAC"
BN"16"87;
%"TAP"
"6","(-1750,2500)","2","mstr_standard","I91";
;
HDL_TAP"TRUE"
BODY_TYPE"PLUMBING"
CDS_LIB"mstr_standard";
"B \NAC \NWC"3;
"S \NAC"
BN"17"86;
%"TAP"
"6","(-1750,2550)","2","mstr_standard","I92";
;
HDL_TAP"TRUE"
BODY_TYPE"PLUMBING"
CDS_LIB"mstr_standard";
"B \NAC \NWC"3;
"S \NAC"
BN"18"83;
%"TAP"
"6","(-1750,2600)","2","mstr_standard","I93";
;
HDL_TAP"TRUE"
BODY_TYPE"PLUMBING"
CDS_LIB"mstr_standard";
"B \NAC \NWC"3;
"S \NAC"
BN"19"91;
%"TAP"
"6","(-1750,2650)","2","mstr_standard","I94";
;
HDL_TAP"TRUE"
BODY_TYPE"PLUMBING"
CDS_LIB"mstr_standard";
"B \NAC \NWC"3;
"S \NAC"
BN"20"90;
%"TAP"
"6","(-1750,2200)","2","mstr_standard","I95";
;
HDL_TAP"TRUE"
BODY_TYPE"PLUMBING"
CDS_LIB"mstr_standard";
"B \NAC \NWC"3;
"S \NAC"
BN"11"79;
%"TAP"
"6","(-1750,2300)","2","mstr_standard","I96";
;
HDL_TAP"TRUE"
BODY_TYPE"PLUMBING"
CDS_LIB"mstr_standard";
"B \NAC \NWC"3;
"S \NAC"
BN"13"77;
%"TAP"
"6","(-1750,2250)","2","mstr_standard","I97";
;
HDL_TAP"TRUE"
BODY_TYPE"PLUMBING"
CDS_LIB"mstr_standard";
"B \NAC \NWC"3;
"S \NAC"
BN"12"78;
%"TAP"
"6","(-1750,2350)","2","mstr_standard","I98";
;
HDL_TAP"TRUE"
BODY_TYPE"PLUMBING"
CDS_LIB"mstr_standard";
"B \NAC \NWC"3;
"S \NAC"
BN"14"84;
%"TAP"
"6","(-1750,2400)","2","mstr_standard","I99";
;
HDL_TAP"TRUE"
BODY_TYPE"PLUMBING"
CDS_LIB"mstr_standard";
"B \NAC \NWC"3;
"S \NAC"
BN"15"85;
END.
